(kicad_pcb
	(version 20260206)
	(generator "pcbnew")
	(generator_version "10.0")
	(general
		(thickness 1.6)
		(legacy_teardrops no)
	)
	(paper "A4")
	(title_block
		(title "baseboard — 13948-1b.1110WZS1818.brd")
		(comment 1 "Honey Badger (Wiwynn) / footprints 1549-1555 of 2523")
	)
	(layers
		(0 "F.Cu" signal "TOP")
		(4 "In1.Cu" signal "L2GND")
		(6 "In2.Cu" signal "L3")
		(8 "In3.Cu" signal "L4VCC")
		(10 "In4.Cu" signal "L5VCC")
		(12 "In5.Cu" signal "L6")
		(14 "In6.Cu" signal "L7GND")
		(2 "B.Cu" signal "BOTTOM")
		(9 "F.Adhes" user "F.Adhesive")
		(11 "B.Adhes" user "B.Adhesive")
		(13 "F.Paste" user "Package Geometry/Pastemask Top")
		(15 "B.Paste" user "Package Geometry/Pastemask Bottom")
		(5 "F.SilkS" user "Ref Des/Silkscreen Top")
		(7 "B.SilkS" user "Ref Des/Silkscreen Bottom")
		(1 "F.Mask" user "Board Geometry/Soldermask Top")
		(3 "B.Mask" user "Board Geometry/Soldermask Bottom")
		(17 "Dwgs.User" user "User.Drawings")
		(19 "Cmts.User" user "User.Comments")
		(21 "Eco1.User" user "User.Eco1")
		(23 "Eco2.User" user "User.Eco2")
		(25 "Edge.Cuts" user "Board Geometry/Outline")
		(27 "Margin" user)
		(31 "F.CrtYd" user "Package Geometry/Place Bound Top")
		(29 "B.CrtYd" user "Package Geometry/Place Bound Bottom")
		(35 "F.Fab" user "Ref Des/Assembly Top")
		(33 "B.Fab" user "Ref Des/Assembly Bottom")
	)
	(footprint ""
		(layer "F.Cu")
		(at 38.354 -214.376 90)
		(property "Reference" "SR842"
			(at 0 0 90)
			(layer "F.SilkS")
			(hide yes)
			(effects
				(font
					(size 1.27 1.27)
				)
			)
		)
		(property "Value" "200KR2F-L-GP"
			(at 0.064008 -3.993896 90)
			(unlocked yes)
			(layer "F.Fab")
			(hide yes)
			(effects
				(font
					(size 1.016 1.016)
					(thickness 0.1524)
				)
			)
		)
		(property "Device Type" "R402H16"
			(at 0.064008 -5.517896 90)
			(unlocked yes)
			(layer "F.Fab")
			(hide yes)
			(effects
				(font
					(size 1.016 1.016)
					(thickness 0.1524)
				)
			)
		)
		(duplicate_pad_numbers_are_jumpers no)
		(fp_line
			(start 0.508 -0.9398)
			(end -0.508 -0.9398)
			(stroke
				(width 0.1524)
				(type default)
			)
			(layer "F.SilkS")
		)
		(fp_line
			(start -0.508 -0.9398)
			(end -0.508 0.9398)
			(stroke
				(width 0.1524)
				(type default)
			)
			(layer "F.SilkS")
		)
		(fp_rect
			(start -0.508 0.9398)
			(end 0.508 -0.9398)
			(stroke
				(width 0)
				(type default)
			)
			(fill no)
			(layer "F.CrtYd")
		)
		(fp_rect
			(start -0.508 0.9398)
			(end 0.508 -0.9398)
			(stroke
				(width 0)
				(type default)
			)
			(fill no)
			(layer "F.Fab")
		)
		(pad "1" smd custom
			(at 0 -0.4445 90)
			(size 0.1397 0.1397)
			(layers "F.Cu" "F.Mask" "F.Paste")
			(net "EXP_I2C_VREF_4")
			(options
				(clearance outline)
				(anchor circle)
			)
			(primitives
				(gr_poly
					(pts
						(arc
							(start -0.1778 -0.2794)
							(mid -0.249642 -0.249642)
							(end -0.2794 -0.1778)
						)
						(arc
							(start -0.2794 0.1778)
							(mid -0.249642 0.249642)
							(end -0.1778 0.2794)
						)
						(arc
							(start 0.1778 0.2794)
							(mid 0.249642 0.249642)
							(end 0.2794 0.1778)
						)
						(arc
							(start 0.2794 -0.1778)
							(mid 0.249642 -0.249642)
							(end 0.1778 -0.2794)
						)
					)
					(width 0)
					(fill yes)
				)
			)
		)
		(pad "2" smd custom
			(at 0 0.4445 90)
			(size 0.1397 0.1397)
			(layers "F.Cu" "F.Mask" "F.Paste")
			(net "P3V3_STBY")
			(options
				(clearance outline)
				(anchor circle)
			)
			(primitives
				(gr_poly
					(pts
						(arc
							(start -0.1778 -0.2794)
							(mid -0.249642 -0.249642)
							(end -0.2794 -0.1778)
						)
						(arc
							(start -0.2794 0.1778)
							(mid -0.249642 0.249642)
							(end -0.1778 0.2794)
						)
						(arc
							(start 0.1778 0.2794)
							(mid 0.249642 0.249642)
							(end 0.2794 0.1778)
						)
						(arc
							(start 0.2794 -0.1778)
							(mid 0.249642 -0.249642)
							(end 0.1778 -0.2794)
						)
					)
					(width 0)
					(fill yes)
				)
			)
		)
	)
	(footprint ""
		(layer "F.Cu")
		(at 95.758 -10.033 180)
		(property "Reference" "PC200"
			(at 0 0 180)
			(layer "F.SilkS")
			(hide yes)
			(effects
				(font
					(size 1.27 1.27)
				)
			)
		)
		(property "Value" "SC22U6D3V6KX-2-GP"
			(at -0.0762 -5.1308 180)
			(unlocked yes)
			(layer "F.Fab")
			(hide yes)
			(effects
				(font
					(size 1.016 1.016)
					(thickness 0.1524)
				)
			)
		)
		(property "Device Type" "C1206H71"
			(at -0.127 -6.6548 180)
			(unlocked yes)
			(layer "F.Fab")
			(hide yes)
			(effects
				(font
					(size 1.016 1.016)
					(thickness 0.1524)
				)
			)
		)
		(duplicate_pad_numbers_are_jumpers no)
		(fp_line
			(start 1.016 2.2352)
			(end -1.016 2.2352)
			(stroke
				(width 0.1524)
				(type default)
			)
			(layer "F.SilkS")
		)
		(fp_line
			(start 1.016 0.8382)
			(end 1.016 2.2352)
			(stroke
				(width 0.1524)
				(type default)
			)
			(layer "F.SilkS")
		)
		(fp_line
			(start 1.016 -2.2352)
			(end 1.016 -0.8382)
			(stroke
				(width 0.1524)
				(type default)
			)
			(layer "F.SilkS")
		)
		(fp_line
			(start -1.016 2.2352)
			(end -1.016 0.8382)
			(stroke
				(width 0.1524)
				(type default)
			)
			(layer "F.SilkS")
		)
		(fp_line
			(start -1.016 -0.8382)
			(end -1.016 -2.2352)
			(stroke
				(width 0.1524)
				(type default)
			)
			(layer "F.SilkS")
		)
		(fp_line
			(start -1.016 -2.2352)
			(end 1.016 -2.2352)
			(stroke
				(width 0.1524)
				(type default)
			)
			(layer "F.SilkS")
		)
		(fp_rect
			(start -1.0922 2.3114)
			(end 1.0922 -2.3114)
			(stroke
				(width 0)
				(type default)
			)
			(fill no)
			(layer "F.CrtYd")
		)
		(fp_poly
			(pts
				(xy 1.0922 -2.3114) (xy 1.0922 2.3114) (xy -1.0922 2.3114) (xy -1.0922 -2.3114)
			)
			(stroke
				(width 0)
				(type default)
			)
			(fill no)
			(layer "F.Fab")
		)
		(pad "1" smd rect
			(at 0 -1.397 180)
			(size 1.651 1.27)
			(layers "F.Cu" "F.Mask" "F.Paste")
			(net "P0V955_C")
		)
		(pad "2" smd rect
			(at 0 1.397 180)
			(size 1.651 1.27)
			(layers "F.Cu" "F.Mask" "F.Paste")
			(net "GND")
		)
	)
	(footprint ""
		(layer "F.Cu")
		(at 80.372966 -88.519 90)
		(property "Reference" "SR828"
			(at 0 0 90)
			(layer "F.SilkS")
			(hide yes)
			(effects
				(font
					(size 1.27 1.27)
				)
			)
		)
		(property "Value" "10R2F-L-GP"
			(at 0.064008 -3.993896 90)
			(unlocked yes)
			(layer "F.Fab")
			(hide yes)
			(effects
				(font
					(size 1.016 1.016)
					(thickness 0.1524)
				)
			)
		)
		(property "Device Type" "R402H14"
			(at 0.064008 -5.517896 90)
			(unlocked yes)
			(layer "F.Fab")
			(hide yes)
			(effects
				(font
					(size 1.016 1.016)
					(thickness 0.1524)
				)
			)
		)
		(duplicate_pad_numbers_are_jumpers no)
		(fp_line
			(start 0.508 -0.9398)
			(end -0.508 -0.9398)
			(stroke
				(width 0.1524)
				(type default)
			)
			(layer "F.SilkS")
		)
		(fp_line
			(start -0.508 -0.9398)
			(end -0.508 0.9398)
			(stroke
				(width 0.1524)
				(type default)
			)
			(layer "F.SilkS")
		)
		(fp_rect
			(start -0.508 0.9398)
			(end 0.508 -0.9398)
			(stroke
				(width 0)
				(type default)
			)
			(fill no)
			(layer "F.CrtYd")
		)
		(fp_rect
			(start -0.508 0.9398)
			(end 0.508 -0.9398)
			(stroke
				(width 0)
				(type default)
			)
			(fill no)
			(layer "F.Fab")
		)
		(pad "1" smd custom
			(at 0 -0.4445 90)
			(size 0.1397 0.1397)
			(layers "F.Cu" "F.Mask" "F.Paste")
			(net "P1V8_E")
			(options
				(clearance outline)
				(anchor circle)
			)
			(primitives
				(gr_poly
					(pts
						(arc
							(start -0.1778 -0.2794)
							(mid -0.249642 -0.249642)
							(end -0.2794 -0.1778)
						)
						(arc
							(start -0.2794 0.1778)
							(mid -0.249642 0.249642)
							(end -0.1778 0.2794)
						)
						(arc
							(start 0.1778 0.2794)
							(mid 0.249642 0.249642)
							(end 0.2794 0.1778)
						)
						(arc
							(start 0.2794 -0.1778)
							(mid 0.249642 -0.249642)
							(end 0.1778 -0.2794)
						)
					)
					(width 0)
					(fill yes)
				)
			)
		)
		(pad "2" smd custom
			(at 0 0.4445 90)
			(size 0.1397 0.1397)
			(layers "F.Cu" "F.Mask" "F.Paste")
			(net "SYSPLL_VDDA18")
			(options
				(clearance outline)
				(anchor circle)
			)
			(primitives
				(gr_poly
					(pts
						(arc
							(start -0.1778 -0.2794)
							(mid -0.249642 -0.249642)
							(end -0.2794 -0.1778)
						)
						(arc
							(start -0.2794 0.1778)
							(mid -0.249642 0.249642)
							(end -0.1778 0.2794)
						)
						(arc
							(start 0.1778 0.2794)
							(mid 0.249642 0.249642)
							(end 0.2794 0.1778)
						)
						(arc
							(start 0.2794 -0.1778)
							(mid 0.249642 -0.249642)
							(end 0.1778 -0.2794)
						)
					)
					(width 0)
					(fill yes)
				)
			)
		)
	)
	(footprint ""
		(layer "F.Cu")
		(at 270.722852 -192.924176 180)
		(property "Reference" "R334"
			(at 0 0 180)
			(layer "F.SilkS")
			(hide yes)
			(effects
				(font
					(size 1.27 1.27)
				)
			)
		)
		(property "Value" "47KR2F-GP"
			(at 0.064008 -3.993896 180)
			(unlocked yes)
			(layer "F.Fab")
			(hide yes)
			(effects
				(font
					(size 1.016 1.016)
					(thickness 0.1524)
				)
			)
		)
		(property "Device Type" "R402H16"
			(at 0.064008 -5.517896 180)
			(unlocked yes)
			(layer "F.Fab")
			(hide yes)
			(effects
				(font
					(size 1.016 1.016)
					(thickness 0.1524)
				)
			)
		)
		(duplicate_pad_numbers_are_jumpers no)
		(fp_line
			(start 0.508 -0.9398)
			(end -0.508 -0.9398)
			(stroke
				(width 0.1524)
				(type default)
			)
			(layer "F.SilkS")
		)
		(fp_line
			(start -0.508 -0.9398)
			(end -0.508 0.9398)
			(stroke
				(width 0.1524)
				(type default)
			)
			(layer "F.SilkS")
		)
		(fp_rect
			(start -0.508 0.9398)
			(end 0.508 -0.9398)
			(stroke
				(width 0)
				(type default)
			)
			(fill no)
			(layer "F.CrtYd")
		)
		(fp_rect
			(start -0.508 0.9398)
			(end 0.508 -0.9398)
			(stroke
				(width 0)
				(type default)
			)
			(fill no)
			(layer "F.Fab")
		)
		(pad "1" smd custom
			(at 0 -0.4445 180)
			(size 0.1397 0.1397)
			(layers "F.Cu" "F.Mask" "F.Paste")
			(net "FM_BMC_RESET_N")
			(options
				(clearance outline)
				(anchor circle)
			)
			(primitives
				(gr_poly
					(pts
						(arc
							(start -0.1778 -0.2794)
							(mid -0.249642 -0.249642)
							(end -0.2794 -0.1778)
						)
						(arc
							(start -0.2794 0.1778)
							(mid -0.249642 0.249642)
							(end -0.1778 0.2794)
						)
						(arc
							(start 0.1778 0.2794)
							(mid 0.249642 0.249642)
							(end 0.2794 0.1778)
						)
						(arc
							(start 0.2794 -0.1778)
							(mid 0.249642 -0.249642)
							(end 0.1778 -0.2794)
						)
					)
					(width 0)
					(fill yes)
				)
			)
		)
		(pad "2" smd custom
			(at 0 0.4445 180)
			(size 0.1397 0.1397)
			(layers "F.Cu" "F.Mask" "F.Paste")
			(net "GND")
			(options
				(clearance outline)
				(anchor circle)
			)
			(primitives
				(gr_poly
					(pts
						(arc
							(start -0.1778 -0.2794)
							(mid -0.249642 -0.249642)
							(end -0.2794 -0.1778)
						)
						(arc
							(start -0.2794 0.1778)
							(mid -0.249642 0.249642)
							(end -0.1778 0.2794)
						)
						(arc
							(start 0.1778 0.2794)
							(mid 0.249642 0.249642)
							(end 0.2794 0.1778)
						)
						(arc
							(start 0.2794 -0.1778)
							(mid 0.249642 -0.249642)
							(end 0.1778 -0.2794)
						)
					)
					(width 0)
					(fill yes)
				)
			)
		)
	)
	(footprint ""
		(layer "F.Cu")
		(at 261.562596 -51.962812 90)
		(property "Reference" "SR720"
			(at 0 0 90)
			(layer "F.SilkS")
			(hide yes)
			(effects
				(font
					(size 1.27 1.27)
				)
			)
		)
		(property "Value" "4K7R2F-GP"
			(at 0.064008 -3.993896 90)
			(unlocked yes)
			(layer "F.Fab")
			(hide yes)
			(effects
				(font
					(size 1.016 1.016)
					(thickness 0.1524)
				)
			)
		)
		(property "Device Type" "R402H16"
			(at 0.064008 -5.517896 90)
			(unlocked yes)
			(layer "F.Fab")
			(hide yes)
			(effects
				(font
					(size 1.016 1.016)
					(thickness 0.1524)
				)
			)
		)
		(duplicate_pad_numbers_are_jumpers no)
		(fp_line
			(start 0.508 -0.9398)
			(end -0.508 -0.9398)
			(stroke
				(width 0.1524)
				(type default)
			)
			(layer "F.SilkS")
		)
		(fp_line
			(start -0.508 -0.9398)
			(end -0.508 0.9398)
			(stroke
				(width 0.1524)
				(type default)
			)
			(layer "F.SilkS")
		)
		(fp_rect
			(start -0.508 0.9398)
			(end 0.508 -0.9398)
			(stroke
				(width 0)
				(type default)
			)
			(fill no)
			(layer "F.CrtYd")
		)
		(fp_rect
			(start -0.508 0.9398)
			(end 0.508 -0.9398)
			(stroke
				(width 0)
				(type default)
			)
			(fill no)
			(layer "F.Fab")
		)
		(pad "1" smd custom
			(at 0 -0.4445 90)
			(size 0.1397 0.1397)
			(layers "F.Cu" "F.Mask" "F.Paste")
			(net "IOC_EEPROM_A1")
			(options
				(clearance outline)
				(anchor circle)
			)
			(primitives
				(gr_poly
					(pts
						(arc
							(start -0.1778 -0.2794)
							(mid -0.249642 -0.249642)
							(end -0.2794 -0.1778)
						)
						(arc
							(start -0.2794 0.1778)
							(mid -0.249642 0.249642)
							(end -0.1778 0.2794)
						)
						(arc
							(start 0.1778 0.2794)
							(mid 0.249642 0.249642)
							(end 0.2794 0.1778)
						)
						(arc
							(start 0.2794 -0.1778)
							(mid 0.249642 -0.249642)
							(end 0.1778 -0.2794)
						)
					)
					(width 0)
					(fill yes)
				)
			)
		)
		(pad "2" smd custom
			(at 0 0.4445 90)
			(size 0.1397 0.1397)
			(layers "F.Cu" "F.Mask" "F.Paste")
			(net "GND")
			(options
				(clearance outline)
				(anchor circle)
			)
			(primitives
				(gr_poly
					(pts
						(arc
							(start -0.1778 -0.2794)
							(mid -0.249642 -0.249642)
							(end -0.2794 -0.1778)
						)
						(arc
							(start -0.2794 0.1778)
							(mid -0.249642 0.249642)
							(end -0.1778 0.2794)
						)
						(arc
							(start 0.1778 0.2794)
							(mid 0.249642 0.249642)
							(end 0.2794 0.1778)
						)
						(arc
							(start 0.2794 -0.1778)
							(mid 0.249642 -0.249642)
							(end 0.1778 -0.2794)
						)
					)
					(width 0)
					(fill yes)
				)
			)
		)
	)
	(footprint ""
		(layer "F.Cu")
		(at 95.89897 -94.234 -90)
		(property "Reference" "SR806"
			(at 0 0 270)
			(layer "F.SilkS")
			(hide yes)
			(effects
				(font
					(size 1.27 1.27)
				)
			)
		)
		(property "Value" "4K75R2F-1-GP"
			(at 0.064008 -3.993896 270)
			(unlocked yes)
			(layer "F.Fab")
			(hide yes)
			(effects
				(font
					(size 1.016 1.016)
					(thickness 0.1524)
				)
			)
		)
		(property "Device Type" "R402H16"
			(at 0.064008 -5.517896 270)
			(unlocked yes)
			(layer "F.Fab")
			(hide yes)
			(effects
				(font
					(size 1.016 1.016)
					(thickness 0.1524)
				)
			)
		)
		(duplicate_pad_numbers_are_jumpers no)
		(fp_line
			(start -0.508 -0.9398)
			(end -0.508 0.9398)
			(stroke
				(width 0.1524)
				(type default)
			)
			(layer "F.SilkS")
		)
		(fp_line
			(start 0.508 -0.9398)
			(end -0.508 -0.9398)
			(stroke
				(width 0.1524)
				(type default)
			)
			(layer "F.SilkS")
		)
		(fp_rect
			(start -0.508 0.9398)
			(end 0.508 -0.9398)
			(stroke
				(width 0)
				(type default)
			)
			(fill no)
			(layer "F.CrtYd")
		)
		(fp_rect
			(start -0.508 0.9398)
			(end 0.508 -0.9398)
			(stroke
				(width 0)
				(type default)
			)
			(fill no)
			(layer "F.Fab")
		)
		(pad "1" smd custom
			(at 0 -0.4445 270)
			(size 0.1397 0.1397)
			(layers "F.Cu" "F.Mask" "F.Paste")
			(net "LSI_SCAN_ENABLE")
			(options
				(clearance outline)
				(anchor circle)
			)
			(primitives
				(gr_poly
					(pts
						(arc
							(start -0.1778 -0.2794)
							(mid -0.249642 -0.249642)
							(end -0.2794 -0.1778)
						)
						(arc
							(start -0.2794 0.1778)
							(mid -0.249642 0.249642)
							(end -0.1778 0.2794)
						)
						(arc
							(start 0.1778 0.2794)
							(mid 0.249642 0.249642)
							(end 0.2794 0.1778)
						)
						(arc
							(start 0.2794 -0.1778)
							(mid 0.249642 -0.249642)
							(end 0.1778 -0.2794)
						)
					)
					(width 0)
					(fill yes)
				)
			)
		)
		(pad "2" smd custom
			(at 0 0.4445 270)
			(size 0.1397 0.1397)
			(layers "F.Cu" "F.Mask" "F.Paste")
			(net "GND")
			(options
				(clearance outline)
				(anchor circle)
			)
			(primitives
				(gr_poly
					(pts
						(arc
							(start -0.1778 -0.2794)
							(mid -0.249642 -0.249642)
							(end -0.2794 -0.1778)
						)
						(arc
							(start -0.2794 0.1778)
							(mid -0.249642 0.249642)
							(end -0.1778 0.2794)
						)
						(arc
							(start 0.1778 0.2794)
							(mid 0.249642 0.249642)
							(end 0.2794 0.1778)
						)
						(arc
							(start 0.2794 -0.1778)
							(mid 0.249642 -0.249642)
							(end 0.1778 -0.2794)
						)
					)
					(width 0)
					(fill yes)
				)
			)
		)
	)
	(footprint ""
		(layer "F.Cu")
		(at 25.604216 -224.21088 -90)
		(property "Reference" "R637"
			(at 0 0 270)
			(layer "F.SilkS")
			(hide yes)
			(effects
				(font
					(size 1.27 1.27)
				)
			)
		)
		(property "Value" "4K7R2F-GP"
			(at 0.064008 -3.993896 270)
			(unlocked yes)
			(layer "F.Fab")
			(hide yes)
			(effects
				(font
					(size 1.016 1.016)
					(thickness 0.1524)
				)
			)
		)
		(property "Device Type" "R402H16"
			(at 0.064008 -5.517896 270)
			(unlocked yes)
			(layer "F.Fab")
			(hide yes)
			(effects
				(font
					(size 1.016 1.016)
					(thickness 0.1524)
				)
			)
		)
		(duplicate_pad_numbers_are_jumpers no)
		(fp_line
			(start -0.508 -0.9398)
			(end -0.508 0.9398)
			(stroke
				(width 0.1524)
				(type default)
			)
			(layer "F.SilkS")
		)
		(fp_line
			(start 0.508 -0.9398)
			(end -0.508 -0.9398)
			(stroke
				(width 0.1524)
				(type default)
			)
			(layer "F.SilkS")
		)
		(fp_rect
			(start -0.508 0.9398)
			(end 0.508 -0.9398)
			(stroke
				(width 0)
				(type default)
			)
			(fill no)
			(layer "F.CrtYd")
		)
		(fp_rect
			(start -0.508 0.9398)
			(end 0.508 -0.9398)
			(stroke
				(width 0)
				(type default)
			)
			(fill no)
			(layer "F.Fab")
		)
		(pad "1" smd custom
			(at 0 -0.4445 270)
			(size 0.1397 0.1397)
			(layers "F.Cu" "F.Mask" "F.Paste")
			(net "IO_EXP_HDD_PWR_A2")
			(options
				(clearance outline)
				(anchor circle)
			)
			(primitives
				(gr_poly
					(pts
						(arc
							(start -0.1778 -0.2794)
							(mid -0.249642 -0.249642)
							(end -0.2794 -0.1778)
						)
						(arc
							(start -0.2794 0.1778)
							(mid -0.249642 0.249642)
							(end -0.1778 0.2794)
						)
						(arc
							(start 0.1778 0.2794)
							(mid 0.249642 0.249642)
							(end 0.2794 0.1778)
						)
						(arc
							(start 0.2794 -0.1778)
							(mid 0.249642 -0.249642)
							(end 0.1778 -0.2794)
						)
					)
					(width 0)
					(fill yes)
				)
			)
		)
		(pad "2" smd custom
			(at 0 0.4445 270)
			(size 0.1397 0.1397)
			(layers "F.Cu" "F.Mask" "F.Paste")
			(net "GND")
			(options
				(clearance outline)
				(anchor circle)
			)
			(primitives
				(gr_poly
					(pts
						(arc
							(start -0.1778 -0.2794)
							(mid -0.249642 -0.249642)
							(end -0.2794 -0.1778)
						)
						(arc
							(start -0.2794 0.1778)
							(mid -0.249642 0.249642)
							(end -0.1778 0.2794)
						)
						(arc
							(start 0.1778 0.2794)
							(mid 0.249642 0.249642)
							(end 0.2794 0.1778)
						)
						(arc
							(start 0.2794 -0.1778)
							(mid 0.249642 -0.249642)
							(end 0.1778 -0.2794)
						)
					)
					(width 0)
					(fill yes)
				)
			)
		)
	)
)
